FILE_TYPE = MULTI_PHYS_TABLE;

PART 'LM75BD'

{========================================================================================}
:VALUE    | PART_TYPE | MATERIAL | PART_NUMBER    = STANDARD    | LIFECYCLE      | PART_NUMBER   | JEDEC_TYPE         | DESCRIPTION                 | MANUFTR | MANUF_PN | RD_CMPLS_LVL | CMPLS_LVL | FROM_PJ       | CLASS | DIP_SMD | DATA             | EE_CHECK_LIST | FP_ECN | PSL | CREATOR | STATUS | MSD | ESD_CDM | ESD_HBM | ESD_MM | PIN_LENGTH_SHORT_PIN | PIN_LENGTH_LONG_PIN | CREATEDAY  ;
{========================================================================================}
 'LM75BD' | 'SMLF'    | 'IC'     | 'AL0075BD000'(!) = ''               | ''               | 'AL0075BD000' |'SO8_1-27_4-9X3-9'| 'IC OTHER (8P) LM75BD(SO8)' | 'NXP'   | 'LM75BD' | 'EP(V1)'     | 'EP(V1)'  | 'F0T-BOB-JON' | 'IC'  | ''      | 'NXP_LM75BD.pdf' | ''            | ''     | ''  | ''      | ''     | ''  | ''      | ''      | ''     | '0 MILS'             | '0 MILS'            | '20211112'
 'LM75BD' | 'SMLF'    | 'EMPTY'  | 'AL0075BD000'(!) = ''               | ''               | 'AL0075BD000' |'SO8_1-27_4-9X3-9'| 'IC OTHER (8P) LM75BD(SO8)' | 'NXP'   | 'LM75BD' | 'EP(V1)'     | 'EP(V1)'  | 'F0T-BOB-JON' | 'IC'  | ''      | 'NXP_LM75BD.pdf' | ''            | ''     | ''  | ''      | ''     | ''  | ''      | ''      | ''     | '0 MILS'             | '0 MILS'            | '20211112'

END_PART

END.

